# BASEBOARD_FAB2 (Tioga Pass) — schematic netlist excerpt (pin names and nets, part order shuffled) for the footprints in the layout excerpt that follows; sources: Cadence DE-HDL packaged netlist, KiCad conversion of Wiwynn_Tioga_Pass_MB.brd

R3D13  RES  240 1.0% EMPTY  pkg 0402  page 90 : A = GND ; B = PD_CPU1_BIST_ENABLE
DS9F1  LED  IC  pkg A1  page 177 : A = FM_RED_LED_ANODE ; C = FM_RED_LED_CATHODE

(kicad_pcb
	(version 20260206)
	(generator "pcbnew")
	(generator_version "10.0")
	(general
		(thickness 1.6)
		(legacy_teardrops no)
	)
	(paper "A4")
	(title_block
		(title "Wiwynn_Tioga_Pass_MB.brd")
		(comment 1 "Tioga Pass / footprints 871-872 of 4770")
	)
	(layers
		(0 "F.Cu" signal "TOP")
		(4 "In1.Cu" signal "L2GND")
		(6 "In2.Cu" signal "L3")
		(8 "In3.Cu" signal "L4GND")
		(10 "In4.Cu" signal "L5")
		(12 "In5.Cu" signal "L6GND")
		(14 "In6.Cu" signal "L7VCC")
		(16 "In7.Cu" signal "L8VCC")
		(18 "In8.Cu" signal "L9GND")
		(20 "In9.Cu" signal "L10")
		(22 "In10.Cu" signal "L11GND")
		(24 "In11.Cu" signal "L12")
		(26 "In12.Cu" signal "L13GND")
		(2 "B.Cu" signal "BOTTOM")
		(9 "F.Adhes" user "F.Adhesive")
		(11 "B.Adhes" user "B.Adhesive")
		(13 "F.Paste" user "Package Geometry/Pastemask Top")
		(15 "B.Paste" user "Package Geometry/Pastemask Bottom")
		(5 "F.SilkS" user "Ref Des/Silkscreen Top")
		(7 "B.SilkS" user "Ref Des/Silkscreen Bottom")
		(1 "F.Mask" user "Board Geometry/Soldermask Top")
		(3 "B.Mask" user "Board Geometry/Soldermask Bottom")
		(17 "Dwgs.User" user "User.Drawings")
		(19 "Cmts.User" user "User.Comments")
		(21 "Eco1.User" user "User.Eco1")
		(23 "Eco2.User" user "User.Eco2")
		(25 "Edge.Cuts" user "Board Geometry/Outline")
		(27 "Margin" user)
		(31 "F.CrtYd" user "Package Geometry/Place Bound Top")
		(29 "B.CrtYd" user "Package Geometry/Place Bound Bottom")
		(35 "F.Fab" user "Ref Des/Assembly Top")
		(33 "B.Fab" user "Ref Des/Assembly Bottom")
	)
	(footprint ""
		(layer "F.Cu")
		(at 116.332 -75.565 90)
		(property "Reference" "R3D13"
			(at 0 0 90)
			(layer "F.SilkS")
			(hide yes)
			(effects
				(font
					(size 1.27 1.27)
				)
			)
		)
		(property "Value" ""
			(at 0 0 90)
			(layer "F.Fab")
			(effects
				(font
					(size 1.27 1.27)
				)
			)
		)
		(duplicate_pad_numbers_are_jumpers no)
		(fp_poly
			(pts
				(xy -0.2794 -0.1016) (xy 0.2794 -0.1016) (xy 0.2794 0.9906) (xy -0.2794 0.9906)
			)
			(stroke
				(width 0)
				(type default)
			)
			(fill no)
			(layer "F.CrtYd")
		)
		(fp_line
			(start 0.2794 -0.1016)
			(end -0.2794 -0.1016)
			(stroke
				(width 0.1)
				(type default)
			)
			(layer "F.Fab")
		)
		(fp_line
			(start -0.2794 -0.1016)
			(end -0.2794 0.9906)
			(stroke
				(width 0.1)
				(type default)
			)
			(layer "F.Fab")
		)
		(fp_line
			(start 0.2794 0.9906)
			(end 0.2794 -0.1016)
			(stroke
				(width 0.1)
				(type default)
			)
			(layer "F.Fab")
		)
		(fp_line
			(start -0.2794 0.9906)
			(end 0.2794 0.9906)
			(stroke
				(width 0.1)
				(type default)
			)
			(layer "F.Fab")
		)
		(pad "1" smd rect
			(at 0 0 90)
			(size 0.508 0.508)
			(layers "F.Cu" "F.Mask" "F.Paste")
			(net "GND")
		)
		(pad "2" smd rect
			(at 0 0.889 90)
			(size 0.508 0.508)
			(layers "F.Cu" "F.Mask" "F.Paste")
			(net "PD_CPU1_BIST_ENABLE")
		)
		(zone
			(layer "F.Cu")
			(hatch none 0.5)
			(connect_pads
				(clearance 0)
			)
			(min_thickness 0.25)
			(keepout
				(tracks allowed)
				(vias not_allowed)
				(pads allowed)
				(copperpour not_allowed)
				(footprints allowed)
			)
			(placement
				(enabled no)
				(sheetname "")
			)
			(fill
				(thermal_gap 0.5)
				(thermal_bridge_width 0.5)
				(island_removal_mode 0)
			)
			(polygon
				(pts
					(xy 116.586 -75.311) (xy 116.586 -75.819) (xy 116.967 -75.819) (xy 116.967 -75.311)
				)
			)
		)
		(zone
			(layer "F.Cu")
			(hatch none 0.5)
			(connect_pads
				(clearance 0)
			)
			(min_thickness 0.25)
			(keepout
				(tracks not_allowed)
				(vias allowed)
				(pads allowed)
				(copperpour not_allowed)
				(footprints allowed)
			)
			(placement
				(enabled no)
				(sheetname "")
			)
			(fill
				(thermal_gap 0.5)
				(thermal_bridge_width 0.5)
				(island_removal_mode 0)
			)
			(polygon
				(pts
					(xy 116.967 -75.311) (xy 116.967 -75.819) (xy 116.586 -75.819) (xy 116.586 -75.311)
				)
			)
		)
	)
	(footprint ""
		(layer "F.Cu")
		(at 454.914 -29.337)
		(property "Reference" "DS9F1"
			(at 0.29083 4.3307 90)
			(unlocked yes)
			(layer "F.SilkS")
			(effects
				(font
					(size 0.7874 0.5842)
					(thickness 0.1524)
				)
			)
		)
		(property "Value" ""
			(at 0 0 0)
			(layer "F.Fab")
			(effects
				(font
					(size 1.27 1.27)
				)
			)
		)
		(duplicate_pad_numbers_are_jumpers no)
		(fp_line
			(start -1.46558 0.060452)
			(end -0.984758 0.060452)
			(stroke
				(width 0.1524)
				(type default)
			)
			(layer "F.SilkS")
		)
		(fp_line
			(start -1.46558 0.893318)
			(end -0.503936 0.893318)
			(stroke
				(width 0.1524)
				(type default)
			)
			(layer "F.SilkS")
		)
		(fp_line
			(start -0.984758 -0.851154)
			(end -0.984758 0.060452)
			(stroke
				(width 0.1524)
				(type default)
			)
			(layer "F.SilkS")
		)
		(fp_line
			(start -0.984758 0.060452)
			(end -0.503936 0.060452)
			(stroke
				(width 0.1524)
				(type default)
			)
			(layer "F.SilkS")
		)
		(fp_line
			(start -0.984758 0.893318)
			(end -1.46558 0.060452)
			(stroke
				(width 0.1524)
				(type default)
			)
			(layer "F.SilkS")
		)
		(fp_line
			(start -0.984758 2.01676)
			(end -0.984758 0.893318)
			(stroke
				(width 0.1524)
				(type default)
			)
			(layer "F.SilkS")
		)
		(fp_line
			(start -0.503936 0.060452)
			(end -0.984758 0.893318)
			(stroke
				(width 0.1524)
				(type default)
			)
			(layer "F.SilkS")
		)
		(fp_rect
			(start -0.4064 1.6891)
			(end 0.4064 0.0889)
			(stroke
				(width 0)
				(type default)
			)
			(fill no)
			(layer "F.CrtYd")
		)
		(fp_line
			(start -1.554734 0.007112)
			(end -0.59309 0.007112)
			(stroke
				(width 0.1)
				(type default)
			)
			(layer "F.Fab")
		)
		(fp_line
			(start -1.554734 0.839978)
			(end -0.59309 0.839978)
			(stroke
				(width 0.1)
				(type default)
			)
			(layer "F.Fab")
		)
		(fp_line
			(start -1.073912 0.007112)
			(end -1.073912 -0.904494)
			(stroke
				(width 0.1)
				(type default)
			)
			(layer "F.Fab")
		)
		(fp_line
			(start -1.073912 0.839978)
			(end -1.554734 0.007112)
			(stroke
				(width 0.1)
				(type default)
			)
			(layer "F.Fab")
		)
		(fp_line
			(start -1.073912 0.839978)
			(end -1.073912 1.96342)
			(stroke
				(width 0.1)
				(type default)
			)
			(layer "F.Fab")
		)
		(fp_line
			(start -0.59309 0.007112)
			(end -1.073912 0.839978)
			(stroke
				(width 0.1)
				(type default)
			)
			(layer "F.Fab")
		)
		(fp_line
			(start -0.4064 0.0889)
			(end 0.4064 0.0889)
			(stroke
				(width 0.1)
				(type default)
			)
			(layer "F.Fab")
		)
		(fp_line
			(start -0.4064 1.6891)
			(end -0.4064 0.0889)
			(stroke
				(width 0.1)
				(type default)
			)
			(layer "F.Fab")
		)
		(fp_line
			(start 0.4064 0.0889)
			(end 0.4064 1.6891)
			(stroke
				(width 0.1)
				(type default)
			)
			(layer "F.Fab")
		)
		(fp_line
			(start 0.4064 1.6891)
			(end -0.4064 1.6891)
			(stroke
				(width 0.1)
				(type default)
			)
			(layer "F.Fab")
		)
		(pad "1" smd rect
			(at 0 0)
			(size 0.762 1.27)
			(layers "F.Cu" "F.Mask" "F.Paste")
			(net "FM_RED_LED_ANODE")
		)
		(pad "2" smd rect
			(at 0 1.778)
			(size 0.762 1.27)
			(layers "F.Cu" "F.Mask" "F.Paste")
			(net "FM_RED_LED_CATHODE")
		)
		(zone
			(layer "F.Cu")
			(hatch none 0.5)
			(connect_pads
				(clearance 0)
			)
			(min_thickness 0.25)
			(keepout
				(tracks not_allowed)
				(vias allowed)
				(pads allowed)
				(copperpour not_allowed)
				(footprints allowed)
			)
			(placement
				(enabled no)
				(sheetname "")
			)
			(fill
				(thermal_gap 0.5)
				(thermal_bridge_width 0.5)
				(island_removal_mode 0)
			)
			(polygon
				(pts
					(xy 454.533 -28.6766) (xy 455.295 -28.6766) (xy 455.295 -28.2194) (xy 454.533 -28.2194)
				)
			)
		)
		(zone
			(layer "F.Cu")
			(hatch none 0.5)
			(connect_pads
				(clearance 0)
			)
			(min_thickness 0.25)
			(keepout
				(tracks allowed)
				(vias not_allowed)
				(pads allowed)
				(copperpour not_allowed)
				(footprints allowed)
			)
			(placement
				(enabled no)
				(sheetname "")
			)
			(fill
				(thermal_gap 0.5)
				(thermal_bridge_width 0.5)
				(island_removal_mode 0)
			)
			(polygon
				(pts
					(xy 454.533 -28.2194) (xy 455.295 -28.2194) (xy 455.295 -28.6766) (xy 454.533 -28.6766)
				)
			)
		)
	)
)
